FILE_TYPE = MACRO_DRAWING;
SET COLOR_WIRE YELLOW;
SET COLOR_PROP ORANGE;
SET COLOR_DOT WHITE;
SET COLOR_ARC YELLOW;
SET COLOR_BODY GREEN;
SET COLOR_NOTE PURPLE;
SET PROP_DISPLAY VALUE;
SET PAGE_NUMBER P4;
FORCEADD QUANTA_TITLE_BLOCK_C..2
(6275 -12450);
FORCEPROP 1 LAST Q_TITLE TABLE OF CONTENT 3/3
J 0
(-3041 -12399);
DISPLAY 2.446809 (-3041 -12399);
PAINT GREEN (-3041 -12399);
FORCEPROP 2 LAST Q_DESIGNER SEAN
J 0
(3076 -12299);
DISPLAY 0.978723 (3076 -12299);
PAINT GREEN (3076 -12299);
FORCEPROP 1 LAST CUSTOM_TXT_CDS <CON_PAGE_NUM> OF <CON_TOTAL_PAGES>
J 0
(5837 -12437);
DISPLAY 0.978723 (5837 -12437);
FORCEPROP 1 LAST CUSTOM_TXT_CDS <Q_REV>
J 0
(6100 -12350);
DISPLAY 1.212766 (6100 -12350);
FORCEPROP 1 LAST CUSTOM_TXT_CDS <Q_PROJ>
J 0
(3900 -12350);
DISPLAY 1.212766 (3900 -12350);
FORCEPROP 1 LAST CUSTOM_TXT_CDS <Q_NUMBER>
J 0
(4875 -12350);
DISPLAY 1.212766 (4875 -12350);
FORCEPROP 1 LAST CUSTOM_TXT_CDS <CON_TC_SNO120>
J 2
(3575 -10775);
FORCEPROP 1 LAST CUSTOM_TXT_CDS <CON_TC_SNO119>
J 2
(3575 -10675);
FORCEPROP 1 LAST CUSTOM_TXT_CDS <CON_TC_SNO118>
J 2
(3575 -10575);
FORCEPROP 1 LAST CUSTOM_TXT_CDS <CON_TC_SNO117>
J 2
(3575 -10475);
FORCEPROP 1 LAST CUSTOM_TXT_CDS <CON_TC_SNO116>
J 2
(3575 -10375);
FORCEPROP 1 LAST CUSTOM_TXT_CDS <CON_TC_SNO115>
J 2
(3575 -10275);
FORCEPROP 1 LAST CUSTOM_TXT_CDS <CON_TC_SNO114>
J 2
(3575 -10175);
FORCEPROP 1 LAST CUSTOM_TXT_CDS <CON_TC_SNO113>
J 2
(3575 -10075);
FORCEPROP 1 LAST CUSTOM_TXT_CDS <CON_TC_SNO112>
J 2
(3575 -9975);
FORCEPROP 1 LAST CUSTOM_TXT_CDS <CON_TC_SNO111>
J 2
(3575 -9875);
FORCEPROP 1 LAST CUSTOM_TXT_CDS <CON_TC_SNO110>
J 2
(3575 -9775);
FORCEPROP 1 LAST CUSTOM_TXT_CDS <CON_TC_SNO109>
J 2
(3575 -9675);
FORCEPROP 1 LAST CUSTOM_TXT_CDS <CON_TC_SNO108>
J 2
(3575 -9575);
FORCEPROP 1 LAST CUSTOM_TXT_CDS <CON_TC_SNO107>
J 2
(3575 -9475);
FORCEPROP 1 LAST CUSTOM_TXT_CDS <CON_TC_SNO106>
J 2
(3575 -9375);
FORCEPROP 1 LAST CUSTOM_TXT_CDS <CON_TC_SNO105>
J 2
(3575 -9275);
FORCEPROP 1 LAST CUSTOM_TXT_CDS <CON_TC_SNO104>
J 2
(3575 -9175);
FORCEPROP 1 LAST CUSTOM_TXT_CDS <CON_TC_SNO103>
J 2
(3575 -9075);
FORCEPROP 1 LAST CUSTOM_TXT_CDS <CON_TC_SNO102>
J 2
(3575 -8975);
FORCEPROP 1 LAST CUSTOM_TXT_CDS <CON_TC_SNO101>
J 2
(3575 -8875);
FORCEPROP 1 LAST CUSTOM_TXT_CDS <CON_TC_SNO100>
J 2
(3575 -8775);
FORCEPROP 1 LAST CUSTOM_TXT_CDS <CON_TC_SNO99>
J 2
(3575 -8675);
FORCEPROP 1 LAST CUSTOM_TXT_CDS <CON_TC_SNO98>
J 2
(3575 -8575);
FORCEPROP 1 LAST CUSTOM_TXT_CDS <CON_TC_SNO97>
J 2
(3575 -8475);
FORCEPROP 1 LAST CUSTOM_TXT_CDS <CON_TC_SNO96>
J 2
(3575 -8375);
FORCEPROP 1 LAST CUSTOM_TXT_CDS <CON_TC_SNO95>
J 2
(3575 -8275);
FORCEPROP 1 LAST CUSTOM_TXT_CDS <CON_TC_SNO94>
J 2
(3575 -8175);
FORCEPROP 1 LAST CUSTOM_TXT_CDS <CON_TC_SNO93>
J 2
(3575 -8075);
FORCEPROP 1 LAST CUSTOM_TXT_CDS <CON_TC_SNO92>
J 2
(3575 -7975);
FORCEPROP 1 LAST CUSTOM_TXT_CDS <CON_TC_SNO91>
J 2
(3575 -7875);
FORCEPROP 1 LAST CUSTOM_TXT_CDS <CON_TC_SNO90>
J 2
(3575 -7775);
FORCEPROP 1 LAST CUSTOM_TXT_CDS <CON_TC_SNO89>
J 2
(3575 -7675);
FORCEPROP 1 LAST CUSTOM_TXT_CDS <CON_TC_SNO88>
J 2
(3575 -7575);
FORCEPROP 1 LAST CUSTOM_TXT_CDS <CON_TC_SNO87>
J 2
(3575 -7475);
FORCEPROP 1 LAST CUSTOM_TXT_CDS <CON_TC_SNO86>
J 2
(3575 -7375);
FORCEPROP 1 LAST CUSTOM_TXT_CDS <CON_TC_SNO85>
J 2
(3575 -7275);
FORCEPROP 1 LAST CUSTOM_TXT_CDS <CON_TC_SNO84>
J 2
(3575 -7175);
FORCEPROP 1 LAST CUSTOM_TXT_CDS <CON_TC_SNO83>
J 2
(3575 -7075);
FORCEPROP 1 LAST CUSTOM_TXT_CDS <CON_TC_SNO82>
J 2
(3575 -6975);
FORCEPROP 1 LAST CUSTOM_TXT_CDS <CON_TC_SNO81>
J 2
(3575 -6875);
FORCEPROP 1 LAST CUSTOM_TXT_CDS <CON_TC_SNO80>
J 2
(1075 -10775);
FORCEPROP 1 LAST CUSTOM_TXT_CDS <CON_TC_SNO79>
J 2
(1075 -10675);
FORCEPROP 1 LAST CUSTOM_TXT_CDS <CON_TC_SNO78>
J 2
(1075 -10575);
FORCEPROP 1 LAST CUSTOM_TXT_CDS <CON_TC_SNO77>
J 2
(1075 -10475);
FORCEPROP 1 LAST CUSTOM_TXT_CDS <CON_TC_SNO76>
J 2
(1075 -10375);
FORCEPROP 1 LAST CUSTOM_TXT_CDS <CON_TC_SNO75>
J 2
(1075 -10275);
FORCEPROP 1 LAST CUSTOM_TXT_CDS <CON_TC_SNO74>
J 2
(1075 -10175);
FORCEPROP 1 LAST CUSTOM_TXT_CDS <CON_TC_SNO73>
J 2
(1075 -10075);
FORCEPROP 1 LAST CUSTOM_TXT_CDS <CON_TC_SNO72>
J 2
(1075 -9975);
FORCEPROP 1 LAST CUSTOM_TXT_CDS <CON_TC_SNO70>
J 2
(1075 -9775);
FORCEPROP 1 LAST CUSTOM_TXT_CDS <CON_TC_SNO69>
J 2
(1075 -9675);
FORCEPROP 1 LAST CUSTOM_TXT_CDS <CON_TC_SNO68>
J 2
(1075 -9575);
FORCEPROP 1 LAST CUSTOM_TXT_CDS <CON_TC_SNO67>
J 2
(1075 -9475);
FORCEPROP 1 LAST CUSTOM_TXT_CDS <CON_TC_SNO66>
J 2
(1075 -9375);
FORCEPROP 1 LAST CUSTOM_TXT_CDS <CON_TC_SNO65>
J 2
(1075 -9275);
FORCEPROP 1 LAST CUSTOM_TXT_CDS <CON_TC_SNO64>
J 2
(1075 -9175);
FORCEPROP 1 LAST CUSTOM_TXT_CDS <CON_TC_SNO63>
J 2
(1075 -9075);
FORCEPROP 1 LAST CUSTOM_TXT_CDS <CON_TC_SNO62>
J 2
(1075 -8975);
FORCEPROP 1 LAST CUSTOM_TXT_CDS <CON_TC_SNO61>
J 2
(1075 -8875);
FORCEPROP 1 LAST CUSTOM_TXT_CDS <CON_TC_SNO60>
J 2
(1075 -8775);
FORCEPROP 1 LAST CUSTOM_TXT_CDS <CON_TC_SNO59>
J 2
(1075 -8675);
FORCEPROP 1 LAST CUSTOM_TXT_CDS <CON_TC_SNO58>
J 2
(1075 -8575);
FORCEPROP 1 LAST CUSTOM_TXT_CDS <CON_TC_SNO57>
J 2
(1075 -8475);
FORCEPROP 1 LAST CUSTOM_TXT_CDS <CON_TC_SNO56>
J 2
(1075 -8375);
FORCEPROP 1 LAST CUSTOM_TXT_CDS <CON_TC_SNO55>
J 2
(1075 -8275);
FORCEPROP 1 LAST CUSTOM_TXT_CDS <CON_TC_SNO54>
J 2
(1075 -8175);
FORCEPROP 1 LAST CUSTOM_TXT_CDS <CON_TC_SNO53>
J 2
(1075 -8075);
FORCEPROP 1 LAST CUSTOM_TXT_CDS <CON_TC_SNO52>
J 2
(1075 -7975);
FORCEPROP 1 LAST CUSTOM_TXT_CDS <CON_TC_SNO51>
J 2
(1075 -7875);
FORCEPROP 1 LAST CUSTOM_TXT_CDS <CON_TC_SNO50>
J 2
(1075 -7775);
FORCEPROP 1 LAST CUSTOM_TXT_CDS <CON_TC_SNO49>
J 2
(1075 -7675);
FORCEPROP 1 LAST CUSTOM_TXT_CDS <CON_TC_SNO48>
J 2
(1075 -7575);
FORCEPROP 1 LAST CUSTOM_TXT_CDS <CON_TC_SNO47>
J 2
(1075 -7475);
FORCEPROP 1 LAST CUSTOM_TXT_CDS <CON_TC_SNM120>
J 0
(3675 -10775);
FORCEPROP 1 LAST CUSTOM_TXT_CDS <CON_TC_SNM119>
J 0
(3675 -10675);
FORCEPROP 1 LAST CUSTOM_TXT_CDS <CON_TC_SNM118>
J 0
(3675 -10575);
FORCEPROP 1 LAST CUSTOM_TXT_CDS <CON_TC_SNM117>
J 0
(3675 -10475);
FORCEPROP 1 LAST CUSTOM_TXT_CDS <CON_TC_SNM116>
J 0
(3675 -10375);
FORCEPROP 1 LAST CUSTOM_TXT_CDS <CON_TC_SNM115>
J 0
(3675 -10275);
FORCEPROP 1 LAST CUSTOM_TXT_CDS <CON_TC_SNM114>
J 0
(3675 -10175);
FORCEPROP 1 LAST CUSTOM_TXT_CDS <CON_TC_SNM113>
J 0
(3675 -10075);
FORCEPROP 1 LAST CUSTOM_TXT_CDS <CON_TC_SNM112>
J 0
(3675 -9975);
FORCEPROP 1 LAST CUSTOM_TXT_CDS <CON_TC_SNM111>
J 0
(3675 -9875);
FORCEPROP 1 LAST CUSTOM_TXT_CDS <CON_TC_SNM109>
J 0
(3675 -9675);
FORCEPROP 1 LAST CUSTOM_TXT_CDS <CON_TC_SNM107>
J 0
(3675 -9475);
FORCEPROP 1 LAST CUSTOM_TXT_CDS <CON_TC_SNM106>
J 0
(3675 -9375);
FORCEPROP 1 LAST CUSTOM_TXT_CDS <CON_TC_SNM105>
J 0
(3675 -9275);
FORCEPROP 1 LAST CUSTOM_TXT_CDS <CON_TC_SNM104>
J 0
(3675 -9175);
FORCEPROP 1 LAST CUSTOM_TXT_CDS <CON_TC_SNM103>
J 0
(3675 -9075);
FORCEPROP 1 LAST CUSTOM_TXT_CDS <CON_TC_SNM102>
J 0
(3675 -8975);
FORCEPROP 1 LAST CUSTOM_TXT_CDS <CON_TC_SNM101>
J 0
(3675 -8875);
FORCEPROP 1 LAST CUSTOM_TXT_CDS <CON_TC_SNM100>
J 0
(3675 -8775);
FORCEPROP 1 LAST CUSTOM_TXT_CDS <CON_TC_SNM99>
J 0
(3675 -8675);
FORCEPROP 1 LAST CUSTOM_TXT_CDS <CON_TC_SNM98>
J 0
(3675 -8575);
FORCEPROP 1 LAST CUSTOM_TXT_CDS <CON_TC_SNM97>
J 0
(3675 -8475);
FORCEPROP 1 LAST CUSTOM_TXT_CDS <CON_TC_SNM96>
J 0
(3675 -8375);
FORCEPROP 1 LAST CUSTOM_TXT_CDS <CON_TC_SNM95>
J 0
(3675 -8275);
FORCEPROP 1 LAST CUSTOM_TXT_CDS <CON_TC_SNM94>
J 0
(3675 -8175);
FORCEPROP 1 LAST CUSTOM_TXT_CDS <CON_TC_SNM93>
J 0
(3675 -8075);
FORCEPROP 1 LAST CUSTOM_TXT_CDS <CON_TC_SNM92>
J 0
(3675 -7975);
FORCEPROP 1 LAST CUSTOM_TXT_CDS <CON_TC_SNM91>
J 0
(3675 -7875);
FORCEPROP 1 LAST CUSTOM_TXT_CDS <CON_TC_SNM90>
J 0
(3675 -7775);
FORCEPROP 1 LAST CUSTOM_TXT_CDS <CON_TC_SNM89>
J 0
(3675 -7675);
FORCEPROP 1 LAST CUSTOM_TXT_CDS <CON_TC_SNM88>
J 0
(3675 -7575);
FORCEPROP 1 LAST CUSTOM_TXT_CDS <CON_TC_SNM87>
J 0
(3675 -7475);
FORCEPROP 1 LAST CUSTOM_TXT_CDS <CON_TC_SNM86>
J 0
(3675 -7375);
FORCEPROP 1 LAST CUSTOM_TXT_CDS <CON_TC_SNM85>
J 0
(3675 -7275);
FORCEPROP 1 LAST CUSTOM_TXT_CDS <CON_TC_SNM84>
J 0
(3675 -7175);
FORCEPROP 1 LAST CUSTOM_TXT_CDS <CON_TC_SNM83>
J 0
(3675 -7075);
FORCEPROP 1 LAST CUSTOM_TXT_CDS <CON_TC_SNM82>
J 0
(3675 -6975);
FORCEPROP 1 LAST CUSTOM_TXT_CDS <CON_TC_SNM81>
J 0
(3675 -6875);
FORCEPROP 1 LAST CUSTOM_TXT_CDS <CON_TC_SNM80>
J 0
(1175 -10775);
FORCEPROP 1 LAST CUSTOM_TXT_CDS <CON_TC_SNM79>
J 0
(1175 -10675);
FORCEPROP 1 LAST CUSTOM_TXT_CDS <CON_TC_SNM78>
J 0
(1175 -10575);
FORCEPROP 1 LAST CUSTOM_TXT_CDS <CON_TC_SNM77>
J 0
(1175 -10475);
FORCEPROP 1 LAST CUSTOM_TXT_CDS <CON_TC_SNM76>
J 0
(1175 -10375);
FORCEPROP 1 LAST CUSTOM_TXT_CDS <CON_TC_SNM75>
J 0
(1175 -10275);
FORCEPROP 1 LAST CUSTOM_TXT_CDS <CON_TC_SNM74>
J 0
(1175 -10175);
FORCEPROP 1 LAST CUSTOM_TXT_CDS <CON_TC_SNM73>
J 0
(1175 -10075);
FORCEPROP 1 LAST CUSTOM_TXT_CDS <CON_TC_SNM72>
J 0
(1175 -9975);
FORCEPROP 1 LAST CUSTOM_TXT_CDS <CON_TC_SNM70>
J 0
(1175 -9775);
FORCEPROP 1 LAST CUSTOM_TXT_CDS <CON_TC_SNM64>
J 0
(1175 -9175);
FORCEPROP 1 LAST CUSTOM_TXT_CDS <CON_TC_SNM63>
J 0
(1175 -9075);
FORCEPROP 1 LAST CUSTOM_TXT_CDS <CON_TC_SNM62>
J 0
(1175 -8975);
FORCEPROP 1 LAST CUSTOM_TXT_CDS <CON_TC_SNM61>
J 0
(1175 -8875);
FORCEPROP 1 LAST CUSTOM_TXT_CDS <CON_TC_SNM60>
J 0
(1175 -8775);
FORCEPROP 1 LAST CUSTOM_TXT_CDS <CON_TC_SNM59>
J 0
(1175 -8675);
FORCEPROP 1 LAST CUSTOM_TXT_CDS <CON_TC_SNM58>
J 0
(1175 -8575);
FORCEPROP 1 LAST CUSTOM_TXT_CDS <CON_TC_SNM57>
J 0
(1175 -8475);
FORCEPROP 1 LAST CUSTOM_TXT_CDS <CON_TC_SNM56>
J 0
(1175 -8375);
FORCEPROP 1 LAST CUSTOM_TXT_CDS <CON_TC_SNM55>
J 0
(1175 -8275);
FORCEPROP 1 LAST CUSTOM_TXT_CDS <CON_TC_SNM54>
J 0
(1175 -8175);
FORCEPROP 1 LAST CUSTOM_TXT_CDS <CON_TC_SNM53>
J 0
(1175 -8075);
FORCEPROP 1 LAST CUSTOM_TXT_CDS <CON_TC_SNM52>
J 0
(1175 -7975);
FORCEPROP 1 LAST CUSTOM_TXT_CDS <CON_TC_SNM51>
J 0
(1175 -7875);
FORCEPROP 1 LAST CUSTOM_TXT_CDS <CON_TC_SNM50>
J 0
(1175 -7775);
FORCEPROP 1 LAST CUSTOM_TXT_CDS <CON_TC_SNM49>
J 0
(1175 -7675);
FORCEPROP 1 LAST CUSTOM_TXT_CDS <CON_TC_SNM48>
J 0
(1175 -7575);
FORCEPROP 1 LAST CUSTOM_TXT_CDS <CON_TC_SNM47>
J 0
(1175 -7475);
FORCEPROP 1 LAST CUSTOM_TXT_CDS <CON_LAST_MODIFIED>
J 0
(4375 -12425);
DISPLAY 0.978723 (4375 -12425);
FORCEPROP 1 LAST CUSTOM_TXT_CDS <CON_TC_SNO46>
J 2
(1075 -7375);
FORCEPROP 1 LAST CUSTOM_TXT_CDS <CON_TC_SNO45>
J 2
(1075 -7275);
FORCEPROP 1 LAST CUSTOM_TXT_CDS <CON_TC_SNO44>
J 2
(1075 -7175);
FORCEPROP 1 LAST CUSTOM_TXT_CDS <CON_TC_SNO43>
J 2
(1075 -7075);
FORCEPROP 1 LAST CUSTOM_TXT_CDS <CON_TC_SNO42>
J 2
(1075 -6975);
FORCEPROP 1 LAST CUSTOM_TXT_CDS <CON_TC_SNO41>
J 2
(1075 -6875);
FORCEPROP 1 LAST CUSTOM_TXT_CDS <CON_TC_SNO40>
J 2
(-1425 -10775);
FORCEPROP 1 LAST CUSTOM_TXT_CDS <CON_TC_SNO39>
J 2
(-1425 -10675);
FORCEPROP 1 LAST CUSTOM_TXT_CDS <CON_TC_SNO38>
J 2
(-1425 -10575);
FORCEPROP 1 LAST CUSTOM_TXT_CDS <CON_TC_SNO35>
J 2
(-1425 -10275);
FORCEPROP 1 LAST CUSTOM_TXT_CDS <CON_TC_SNO34>
J 2
(-1425 -10175);
FORCEPROP 1 LAST CUSTOM_TXT_CDS <CON_TC_SNO33>
J 2
(-1425 -10075);
FORCEPROP 1 LAST CUSTOM_TXT_CDS <CON_TC_SNO32>
J 2
(-1425 -9975);
FORCEPROP 1 LAST CUSTOM_TXT_CDS <CON_TC_SNO31>
J 2
(-1425 -9875);
FORCEPROP 1 LAST CUSTOM_TXT_CDS <CON_TC_SNO30>
J 2
(-1425 -9775);
FORCEPROP 1 LAST CUSTOM_TXT_CDS <CON_TC_SNO27>
J 2
(-1425 -9475);
FORCEPROP 1 LAST CUSTOM_TXT_CDS <CON_TC_SNO25>
J 2
(-1425 -9275);
FORCEPROP 1 LAST CUSTOM_TXT_CDS <CON_TC_SNO24>
J 2
(-1425 -9175);
FORCEPROP 1 LAST CUSTOM_TXT_CDS <CON_TC_SNO23>
J 2
(-1425 -9075);
FORCEPROP 1 LAST CUSTOM_TXT_CDS <CON_TC_SNO22>
J 2
(-1425 -8975);
FORCEPROP 1 LAST CUSTOM_TXT_CDS <CON_TC_SNO20>
J 2
(-1425 -8775);
FORCEPROP 1 LAST CUSTOM_TXT_CDS <CON_TC_SNO19>
J 2
(-1425 -8675);
FORCEPROP 1 LAST CUSTOM_TXT_CDS <CON_TC_SNO17>
J 2
(-1425 -8475);
FORCEPROP 1 LAST CUSTOM_TXT_CDS <CON_TC_SNO16>
J 2
(-1425 -8375);
FORCEPROP 1 LAST CUSTOM_TXT_CDS <CON_TC_SNO15>
J 2
(-1425 -8275);
FORCEPROP 1 LAST CUSTOM_TXT_CDS <CON_TC_SNO14>
J 2
(-1425 -8175);
FORCEPROP 1 LAST CUSTOM_TXT_CDS <CON_TC_SNO13>
J 2
(-1425 -8075);
FORCEPROP 1 LAST CUSTOM_TXT_CDS <CON_TC_SNO12>
J 2
(-1425 -7975);
FORCEPROP 1 LAST CUSTOM_TXT_CDS <CON_TC_SNO11>
J 2
(-1425 -7875);
FORCEPROP 1 LAST CUSTOM_TXT_CDS <CON_TC_SNO10>
J 2
(-1425 -7775);
FORCEPROP 1 LAST CUSTOM_TXT_CDS <CON_TC_SNO9>
J 2
(-1425 -7675);
FORCEPROP 1 LAST CUSTOM_TXT_CDS <CON_TC_SNO8>
J 2
(-1425 -7575);
FORCEPROP 1 LAST CUSTOM_TXT_CDS <CON_TC_SNO7>
J 2
(-1425 -7475);
FORCEPROP 1 LAST CUSTOM_TXT_CDS <CON_TC_SNO6>
J 2
(-1425 -7375);
FORCEPROP 1 LAST CUSTOM_TXT_CDS <CON_TC_SNO5>
J 2
(-1425 -7275);
FORCEPROP 1 LAST CUSTOM_TXT_CDS <CON_TC_SNO4>
J 2
(-1425 -7175);
FORCEPROP 1 LAST CUSTOM_TXT_CDS <CON_TC_SNO3>
J 2
(-1425 -7075);
FORCEPROP 1 LAST CUSTOM_TXT_CDS <CON_TC_SNO2>
J 2
(-1425 -6975);
FORCEPROP 1 LAST CUSTOM_TXT_CDS <CON_TC_SNO1>
J 2
(-1425 -6875);
FORCEPROP 1 LAST CUSTOM_TXT_CDS <CON_TC_SNM46>
J 0
(1175 -7375);
FORCEPROP 1 LAST CUSTOM_TXT_CDS <CON_TC_SNM45>
J 0
(1175 -7275);
FORCEPROP 1 LAST CUSTOM_TXT_CDS <CON_TC_SNM44>
J 0
(1175 -7175);
FORCEPROP 1 LAST CUSTOM_TXT_CDS <CON_TC_SNM43>
J 0
(1175 -7075);
FORCEPROP 1 LAST CUSTOM_TXT_CDS <CON_TC_SNM42>
J 0
(1175 -6975);
FORCEPROP 1 LAST CUSTOM_TXT_CDS <CON_TC_SNM41>
J 0
(1175 -6875);
FORCEPROP 1 LAST CUSTOM_TXT_CDS <CON_TC_SNM37>
J 0
(-1325 -10475);
FORCEPROP 1 LAST CUSTOM_TXT_CDS <CON_TC_SNM33>
J 0
(-1325 -10075);
FORCEPROP 1 LAST CUSTOM_TXT_CDS <CON_TC_SNM26>
J 0
(-1325 -9375);
FORCEPROP 1 LAST CUSTOM_TXT_CDS <CON_TC_SNM25>
J 0
(-1325 -9275);
FORCEPROP 1 LAST CUSTOM_TXT_CDS <CON_TC_SNM24>
J 0
(-1325 -9175);
FORCEPROP 1 LAST CUSTOM_TXT_CDS <CON_TC_SNM23>
J 0
(-1325 -9075);
FORCEPROP 1 LAST CUSTOM_TXT_CDS <CON_TC_SNM22>
J 0
(-1325 -8975);
FORCEPROP 1 LAST CUSTOM_TXT_CDS <CON_TC_SNM20>
J 0
(-1325 -8775);
FORCEPROP 1 LAST CUSTOM_TXT_CDS <CON_TC_SNM17>
J 0
(-1325 -8475);
FORCEPROP 1 LAST CUSTOM_TXT_CDS <CON_TC_SNM16>
J 0
(-1325 -8375);
FORCEPROP 1 LAST CUSTOM_TXT_CDS <CON_TC_SNM15>
J 0
(-1325 -8275);
FORCEPROP 1 LAST CUSTOM_TXT_CDS <CON_TC_SNM14>
J 0
(-1325 -8175);
FORCEPROP 1 LAST CUSTOM_TXT_CDS <CON_TC_SNM13>
J 0
(-1325 -8075);
FORCEPROP 1 LAST CUSTOM_TXT_CDS <CON_TC_SNM12>
J 0
(-1325 -7975);
FORCEPROP 1 LAST CUSTOM_TXT_CDS <CON_TC_SNM11>
J 0
(-1325 -7875);
FORCEPROP 1 LAST CUSTOM_TXT_CDS <CON_TC_SNM10>
J 0
(-1325 -7775);
FORCEPROP 1 LAST CUSTOM_TXT_CDS <CON_TC_SNM9>
J 0
(-1325 -7675);
FORCEPROP 1 LAST CUSTOM_TXT_CDS <CON_TC_SNM8>
J 0
(-1325 -7575);
FORCEPROP 1 LAST CUSTOM_TXT_CDS <CON_TC_SNM7>
J 0
(-1325 -7475);
FORCEPROP 1 LAST CUSTOM_TXT_CDS <CON_TC_SNM6>
J 0
(-1325 -7375);
FORCEPROP 1 LAST CUSTOM_TXT_CDS <CON_TC_SNM5>
J 0
(-1325 -7275);
FORCEPROP 1 LAST CUSTOM_TXT_CDS <CON_TC_SNM4>
J 0
(-1325 -7175);
FORCEPROP 1 LAST CUSTOM_TXT_CDS <CON_TC_SNM3>
J 0
(-1325 -7075);
FORCEPROP 1 LAST CUSTOM_TXT_CDS <CON_TC_SNM2>
J 0
(-1325 -6975);
FORCEPROP 1 LAST CUSTOM_TXT_CDS <CON_TC_SNM1>
J 0
(-1325 -6875);
FORCEPROP 1 LAST CUSTOM_TXT_CDS <CON_TC_SNO26>
J 2
(-1425 -9375);
FORCEPROP 1 LAST CUSTOM_TXT_CDS <CON_TC_SNM27>
J 0
(-1325 -9475);
FORCEPROP 1 LAST CUSTOM_TXT_CDS <CON_TC_SNM28>
J 0
(-1325 -9575);
FORCEPROP 1 LAST CUSTOM_TXT_CDS <CON_TC_SNM29>
J 0
(-1325 -9675);
FORCEPROP 1 LAST CUSTOM_TXT_CDS <CON_TC_SNO71>
J 2
(1075 -9875);
FORCEPROP 1 LAST CUSTOM_TXT_CDS <CON_TC_SNM108>
J 0
(3675 -9575);
FORCEPROP 1 LAST CUSTOM_TXT_CDS <CON_TC_SNM71>
J 0
(1175 -9875);
FORCEPROP 1 LAST CUSTOM_TXT_CDS <CON_TC_SNM110>
J 0
(3675 -9775);
FORCEPROP 1 LAST CUSTOM_TXT_CDS <CON_TC_SNM69>
J 0
(1175 -9675);
FORCEPROP 1 LAST CUSTOM_TXT_CDS <CON_TC_SNM68>
J 0
(1175 -9575);
FORCEPROP 1 LAST CUSTOM_TXT_CDS <CON_TC_SNM67>
J 0
(1175 -9475);
FORCEPROP 1 LAST CUSTOM_TXT_CDS <CON_TC_SNM66>
J 0
(1175 -9375);
FORCEPROP 1 LAST CUSTOM_TXT_CDS <CON_TC_SNM65>
J 0
(1175 -9275);
FORCEPROP 1 LAST CUSTOM_TXT_CDS <CON_TC_SNO18>
J 2
(-1425 -8575);
FORCEPROP 1 LAST CUSTOM_TXT_CDS <CON_TC_SNM18>
J 0
(-1325 -8575);
FORCEPROP 1 LAST CUSTOM_TXT_CDS <CON_TC_SNM19>
J 0
(-1325 -8675);
FORCEPROP 1 LAST CUSTOM_TXT_CDS <CON_TC_SNM21>
J 0
(-1325 -8875);
FORCEPROP 1 LAST CUSTOM_TXT_CDS <CON_TC_SNO21>
J 2
(-1425 -8875);
FORCEPROP 1 LAST CUSTOM_TXT_CDS <CON_TC_SNO28>
J 2
(-1425 -9575);
FORCEPROP 1 LAST CUSTOM_TXT_CDS <CON_TC_SNO29>
J 2
(-1425 -9675);
FORCEPROP 1 LAST CUSTOM_TXT_CDS <CON_TC_SNM30>
J 0
(-1325 -9775);
FORCEPROP 1 LAST CUSTOM_TXT_CDS <CON_TC_SNM31>
J 0
(-1325 -9875);
FORCEPROP 1 LAST CUSTOM_TXT_CDS <CON_TC_SNM32>
J 0
(-1325 -9975);
FORCEPROP 1 LAST CUSTOM_TXT_CDS <CON_TC_SNM34>
J 0
(-1325 -10175);
FORCEPROP 1 LAST CUSTOM_TXT_CDS <CON_TC_SNM35>
J 0
(-1325 -10275);
FORCEPROP 1 LAST CUSTOM_TXT_CDS <CON_TC_SNM36>
J 0
(-1325 -10375);
FORCEPROP 1 LAST CUSTOM_TXT_CDS <CON_TC_SNO36>
J 2
(-1425 -10375);
FORCEPROP 1 LAST CUSTOM_TXT_CDS <CON_TC_SNO37>
J 2
(-1425 -10475);
FORCEPROP 1 LAST CUSTOM_TXT_CDS <CON_TC_SNM38>
J 0
(-1325 -10575);
FORCEPROP 1 LAST CUSTOM_TXT_CDS <CON_TC_SNM39>
J 0
(-1325 -10675);
FORCEPROP 1 LAST CUSTOM_TXT_CDS <CON_TC_SNM40>
J 0
(-1325 -10775);
FORCEPROP 2 LAST Q_DEPT 
J 1
(2524 -12401);
DISPLAY 1.957447 (2524 -12401);
PAINT GREEN (2524 -12401);
FORCEPROP 2 LAST CDS_LIB pure_quanta
J 0
(6275 -12450);
PAINT MONO (6275 -12450);
DISPLAY INVISIBLE (6275 -12450);
FORCEPROP 1 LAST COMMENT_BODY TRUE
J 0
(5126 -12424);
DISPLAY 0.978723 (5126 -12424);
PAINT GREEN (5126 -12424);
DISPLAY INVISIBLE (5126 -12424);
FORCEPROP 1 LAST TOC_SYMBOL TRUE
J 0
(-2899 -5998);
DISPLAY 0.978723 (-2899 -5998);
PAINT GREEN (-2899 -5998);
DISPLAY INVISIBLE (-2899 -5998);
FORCEPROP 2 LAST PAGE_BORDER TRUE
J 0
(-1615 -7200);
DISPLAY 0.638298 (-1615 -7200);
PAINT PINK (-1615 -7200);
DISPLAY INVISIBLE (-1615 -7200);
FORCEPROP 2 LAST CDS_XR_PAGE_TITLE CR-4 : @S9S_MB_2U_LIB.S9S_MB_2U(SCH_1):PAGE4
J 0
(-1615 -7200);
DISPLAY 0.638298 (-1615 -7200);
PAINT PINK (-1615 -7200);
DISPLAY INVISIBLE (-1615 -7200);
FORCEPROP 2 LAST CUSTOM_TXT_CDS <XR_PAGE_TITLE>
J 0
(-1615 -7200);
DISPLAY 0.638298 (-1615 -7200);
PAINT PINK (-1615 -7200);
DISPLAY INVISIBLE (-1615 -7200);
FORCEPROP 0 LAST CDS_CON_LAST_MODIFIED Thu Aug 24 16:11:57 2023
J 0
(4375 -12425);
PAINT MONO (4375 -12425);
DISPLAY INVISIBLE (4375 -12425);
QUIT
